# S9S_MB_2U (Grand Teton) — schematic netlist excerpt (pin names and nets, part order shuffled) for the footprints in the layout excerpt that follows; sources: Cadence DE-HDL packaged netlist, KiCad conversion of 03242023_DA0F0TMBIJ0_F0T_Motherboard_J_brd_V01_OCP.brd

X6  TP_TDR_4P_FTS  TP_TDR_4P_DIP EMPTY  pkg TH  page 309
  S1  = TDR_DIFF_85_BOT_DP
  P1  = T1_GND
  P2  = T1_GND
  S2  = TDR_DIFF_85_BOT_DN

C28  Q_CAP  10UF 16V 10% X6S  pkg C0805  page 90 : A = P12V_S3_AUX_CPU0_NVDIMM ; B = GND

(kicad_pcb
	(version 20260206)
	(generator "pcbnew")
	(generator_version "10.0")
	(general
		(thickness 1.6)
		(legacy_teardrops no)
	)
	(paper "A4")
	(title_block
		(title "03242023_DA0F0TMBIJ0_F0T_Motherboard_J_brd_V01_OCP.brd")
		(comment 1 "Grand Teton / footprints 4954-4955 of 6105")
	)
	(layers
		(0 "F.Cu" signal "TOP")
		(4 "In1.Cu" signal "GND")
		(6 "In2.Cu" signal "IN1")
		(8 "In3.Cu" signal "GND1")
		(10 "In4.Cu" signal "IN2")
		(12 "In5.Cu" signal "GND2")
		(14 "In6.Cu" signal "IN3")
		(16 "In7.Cu" signal "GND3")
		(18 "In8.Cu" signal "VCC")
		(20 "In9.Cu" signal "VCC1")
		(22 "In10.Cu" signal "GND4")
		(24 "In11.Cu" signal "IN4")
		(26 "In12.Cu" signal "GND5")
		(28 "In13.Cu" signal "IN5")
		(30 "In14.Cu" signal "GND6")
		(32 "In15.Cu" signal "IN6")
		(34 "In16.Cu" signal "GND7")
		(2 "B.Cu" signal "BOTTOM")
		(9 "F.Adhes" user "F.Adhesive")
		(11 "B.Adhes" user "B.Adhesive")
		(13 "F.Paste" user "Package Geometry/Pastemask Top")
		(15 "B.Paste" user "Package Geometry/Pastemask Bottom")
		(5 "F.SilkS" user "Ref Des/Silkscreen Top")
		(7 "B.SilkS" user "Ref Des/Silkscreen Bottom")
		(1 "F.Mask" user "Board Geometry/Soldermask Top")
		(3 "B.Mask" user "Board Geometry/Soldermask Bottom")
		(17 "Dwgs.User" user "User.Drawings")
		(19 "Cmts.User" user "User.Comments")
		(21 "Eco1.User" user "User.Eco1")
		(23 "Eco2.User" user "User.Eco2")
		(25 "Edge.Cuts" user "Board Geometry/Outline")
		(27 "Margin" user)
		(31 "F.CrtYd" user "Package Geometry/Place Bound Top")
		(29 "B.CrtYd" user "Package Geometry/Place Bound Bottom")
		(35 "F.Fab" user "Ref Des/Assembly Top")
		(33 "B.Fab" user "Ref Des/Assembly Bottom")
	)
	(footprint ""
		(layer "B.Cu")
		(at 488.03433 -153.128472 90)
		(property "Reference" "X6"
			(at 1.617218 2.436622 270)
			(unlocked yes)
			(layer "B.SilkS")
			(effects
				(font
					(size 0.7874 0.5842)
					(thickness 0.1524)
				)
				(justify left mirror)
			)
		)
		(property "Value" ""
			(at 0 0 90)
			(layer "B.Fab")
			(effects
				(font
					(size 1.27 1.27)
				)
				(justify mirror)
			)
		)
		(property "Device Type" "TP_TDR_4P_FTS_MPKT4_H025P0200_I"
			(at -1.30175 1.27 0)
			(unlocked yes)
			(layer "B.Fab")
			(hide yes)
			(effects
				(font
					(size 0.635 0.4064)
					(thickness 0.1524)
				)
				(justify mirror)
			)
		)
		(property "User Part Number" "TP15"
			(at -1.30175 1.27 0)
			(unlocked yes)
			(layer "Cmts.User")
			(hide yes)
			(effects
				(font
					(size 0.635 0.4064)
					(thickness 0.1524)
				)
				(justify mirror)
			)
		)
		(duplicate_pad_numbers_are_jumpers no)
		(fp_line
			(start 0 -1.27)
			(end 0 -0.635)
			(stroke
				(width 0.1524)
				(type default)
			)
			(layer "B.SilkS")
		)
		(fp_line
			(start -2.54 -1.27)
			(end 0 -1.27)
			(stroke
				(width 0.1524)
				(type default)
			)
			(layer "B.SilkS")
		)
		(fp_line
			(start -2.54 -1.1303)
			(end -2.54 -1.27)
			(stroke
				(width 0.1524)
				(type default)
			)
			(layer "B.SilkS")
		)
		(fp_line
			(start 0 0.635)
			(end 0 1.905)
			(stroke
				(width 0.1524)
				(type default)
			)
			(layer "B.SilkS")
		)
		(fp_line
			(start -2.54 1.4097)
			(end -2.54 1.1303)
			(stroke
				(width 0.1524)
				(type default)
			)
			(layer "B.SilkS")
		)
		(fp_line
			(start 0 3.175)
			(end 0 3.81)
			(stroke
				(width 0.1524)
				(type default)
			)
			(layer "B.SilkS")
		)
		(fp_line
			(start 0 3.81)
			(end -2.54 3.81)
			(stroke
				(width 0.1524)
				(type default)
			)
			(layer "B.SilkS")
		)
		(fp_line
			(start -2.54 3.81)
			(end -2.54 3.6703)
			(stroke
				(width 0.1524)
				(type default)
			)
			(layer "B.SilkS")
		)
		(fp_poly
			(pts
				(xy 2.790952 -0.930402) (xy 2.790952 0.593598) (xy 1.266952 -0.168402)
			)
			(stroke
				(width 0)
				(type default)
			)
			(fill yes)
			(layer "B.SilkS")
		)
		(fp_line
			(start 0 -1.27)
			(end 0 3.81)
			(stroke
				(width 0.1)
				(type default)
			)
			(layer "B.Fab")
		)
		(fp_line
			(start -2.54 -1.27)
			(end 0 -1.27)
			(stroke
				(width 0.1)
				(type default)
			)
			(layer "B.Fab")
		)
		(fp_line
			(start 0 3.81)
			(end -2.54 3.81)
			(stroke
				(width 0.1)
				(type default)
			)
			(layer "B.Fab")
		)
		(fp_line
			(start -2.54 3.81)
			(end -2.54 -1.27)
			(stroke
				(width 0.1)
				(type default)
			)
			(layer "B.Fab")
		)
		(fp_poly
			(pts
				(xy 0.761746 0) (xy 2.285746 -0.762) (xy 2.285746 0.762)
			)
			(stroke
				(width 0)
				(type default)
			)
			(fill yes)
			(layer "B.Fab")
		)
		(pad "1" thru_hole circle
			(at 0 0 270)
			(size 1.0033 1.0033)
			(drill 0.249936)
			(layers "*.Cu" "*.Mask")
			(remove_unused_layers no)
			(net "TDR_DIFF_85_BOT_DP")
			(clearance 0.10795)
			(padstack
				(mode front_inner_back)
				(layer "Inner"
					(shape circle)
					(size 0.8001 0.8001)
					(clearance 0.1524)
				)
				(layer "B.Cu"
					(shape circle)
					(size 1.0033 1.0033)
					(thermal_gap 0.10795)
					(clearance 0.10795)
				)
			)
		)
		(pad "2" thru_hole circle
			(at -2.54 0 270)
			(size 1.9939 1.9939)
			(drill 0.249936)
			(layers "*.Cu" "*.Mask")
			(remove_unused_layers no)
			(net "T1_GND")
			(clearance 0.10795)
			(padstack
				(mode front_inner_back)
				(layer "Inner"
					(shape circle)
					(size 0.8001 0.8001)
					(clearance 0.1524)
				)
				(layer "B.Cu"
					(shape circle)
					(size 1.9939 1.9939)
					(thermal_gap 0.10795)
					(clearance 0.10795)
				)
			)
		)
		(pad "3" thru_hole circle
			(at -2.54 2.54 270)
			(size 1.9939 1.9939)
			(drill 0.249936)
			(layers "*.Cu" "*.Mask")
			(remove_unused_layers no)
			(net "T1_GND")
			(clearance 0.10795)
			(padstack
				(mode front_inner_back)
				(layer "Inner"
					(shape circle)
					(size 0.8001 0.8001)
					(clearance 0.1524)
				)
				(layer "B.Cu"
					(shape circle)
					(size 1.9939 1.9939)
					(thermal_gap 0.10795)
					(clearance 0.10795)
				)
			)
		)
		(pad "4" thru_hole circle
			(at 0 2.54 270)
			(size 1.0033 1.0033)
			(drill 0.249936)
			(layers "*.Cu" "*.Mask")
			(remove_unused_layers no)
			(net "TDR_DIFF_85_BOT_DN")
			(clearance 0.10795)
			(padstack
				(mode front_inner_back)
				(layer "Inner"
					(shape circle)
					(size 0.8001 0.8001)
					(clearance 0.1524)
				)
				(layer "B.Cu"
					(shape circle)
					(size 1.0033 1.0033)
					(thermal_gap 0.10795)
					(clearance 0.10795)
				)
			)
		)
	)
	(footprint ""
		(layer "B.Cu")
		(at 414.309814 -321.549776 -90)
		(property "Reference" "C28"
			(at 0 0 90)
			(layer "B.SilkS")
			(hide yes)
			(effects
				(font
					(size 1.27 1.27)
				)
				(justify mirror)
			)
		)
		(property "Value" ""
			(at 0 0 90)
			(layer "B.Fab")
			(effects
				(font
					(size 1.27 1.27)
				)
				(justify mirror)
			)
		)
		(duplicate_pad_numbers_are_jumpers no)
		(fp_line
			(start -1.524 0.762)
			(end 1.524 0.762)
			(stroke
				(width 0.1524)
				(type default)
			)
			(layer "B.SilkS")
		)
		(fp_line
			(start 1.524 0.762)
			(end 1.524 -0.762)
			(stroke
				(width 0.1524)
				(type default)
			)
			(layer "B.SilkS")
		)
		(fp_line
			(start -1.524 -0.762)
			(end -1.524 0.762)
			(stroke
				(width 0.1524)
				(type default)
			)
			(layer "B.SilkS")
		)
		(fp_line
			(start 1.524 -0.762)
			(end -1.524 -0.762)
			(stroke
				(width 0.1524)
				(type default)
			)
			(layer "B.SilkS")
		)
		(fp_line
			(start -1.1049 0.724916)
			(end -1.1049 -0.724916)
			(stroke
				(width 0.1)
				(type default)
			)
			(layer "B.Fab")
		)
		(fp_line
			(start 1.1049 0.724916)
			(end -1.1049 0.724916)
			(stroke
				(width 0.1)
				(type default)
			)
			(layer "B.Fab")
		)
		(fp_line
			(start -1.1049 -0.724916)
			(end 1.1049 -0.724916)
			(stroke
				(width 0.1)
				(type default)
			)
			(layer "B.Fab")
		)
		(fp_line
			(start 1.1049 -0.724916)
			(end 1.1049 0.724916)
			(stroke
				(width 0.1)
				(type default)
			)
			(layer "B.Fab")
		)
		(pad "1" smd rect
			(at 0.889 0 270)
			(size 1.016 1.27)
			(layers "B.Cu" "B.Mask" "B.Paste")
			(net "P12V_S3_AUX_CPU0_NVDIMM")
		)
		(pad "2" smd rect
			(at -0.889 0 270)
			(size 1.016 1.27)
			(layers "B.Cu" "B.Mask" "B.Paste")
			(net "GND")
		)
	)
)
